# S9S_MB_2U (Grand Teton) — schematic netlist excerpt (pin names and nets, part order shuffled) for the footprints in the layout excerpt that follows; sources: Cadence DE-HDL packaged netlist, KiCad conversion of 03242023_DA0F0TMBIJ0_F0T_Motherboard_J_brd_V01_OCP.brd

PC275_P0_3  Q_CAP  3300PF 50V 10% X7R  pkg 0402  page 268 : A = SW_P12V_PVCCIN_CPU0_FLT ; B = GND
C2376  Q_CAP  0.1UF 25V 10% X7R  pkg 0402  page 158 : A = P3V3_AUX ; B = GND

(kicad_pcb
	(version 20260206)
	(generator "pcbnew")
	(generator_version "10.0")
	(general
		(thickness 1.6)
		(legacy_teardrops no)
	)
	(paper "A4")
	(title_block
		(title "03242023_DA0F0TMBIJ0_F0T_Motherboard_J_brd_V01_OCP.brd")
		(comment 1 "Grand Teton / footprints 848-849 of 6105")
	)
	(layers
		(0 "F.Cu" signal "TOP")
		(4 "In1.Cu" signal "GND")
		(6 "In2.Cu" signal "IN1")
		(8 "In3.Cu" signal "GND1")
		(10 "In4.Cu" signal "IN2")
		(12 "In5.Cu" signal "GND2")
		(14 "In6.Cu" signal "IN3")
		(16 "In7.Cu" signal "GND3")
		(18 "In8.Cu" signal "VCC")
		(20 "In9.Cu" signal "VCC1")
		(22 "In10.Cu" signal "GND4")
		(24 "In11.Cu" signal "IN4")
		(26 "In12.Cu" signal "GND5")
		(28 "In13.Cu" signal "IN5")
		(30 "In14.Cu" signal "GND6")
		(32 "In15.Cu" signal "IN6")
		(34 "In16.Cu" signal "GND7")
		(2 "B.Cu" signal "BOTTOM")
		(9 "F.Adhes" user "F.Adhesive")
		(11 "B.Adhes" user "B.Adhesive")
		(13 "F.Paste" user "Package Geometry/Pastemask Top")
		(15 "B.Paste" user "Package Geometry/Pastemask Bottom")
		(5 "F.SilkS" user "Ref Des/Silkscreen Top")
		(7 "B.SilkS" user "Ref Des/Silkscreen Bottom")
		(1 "F.Mask" user "Board Geometry/Soldermask Top")
		(3 "B.Mask" user "Board Geometry/Soldermask Bottom")
		(17 "Dwgs.User" user "User.Drawings")
		(19 "Cmts.User" user "User.Comments")
		(21 "Eco1.User" user "User.Eco1")
		(23 "Eco2.User" user "User.Eco2")
		(25 "Edge.Cuts" user "Board Geometry/Outline")
		(27 "Margin" user)
		(31 "F.CrtYd" user "Package Geometry/Place Bound Top")
		(29 "B.CrtYd" user "Package Geometry/Place Bound Bottom")
		(35 "F.Fab" user "Ref Des/Assembly Top")
		(33 "B.Fab" user "Ref Des/Assembly Bottom")
	)
	(footprint ""
		(layer "F.Cu")
		(at 365.308134 -337.955382)
		(property "Reference" "PC275_P0_3"
			(at 0 0 0)
			(layer "F.SilkS")
			(hide yes)
			(effects
				(font
					(size 1.27 1.27)
				)
			)
		)
		(property "Value" ""
			(at 0 0 0)
			(layer "F.Fab")
			(effects
				(font
					(size 1.27 1.27)
				)
			)
		)
		(duplicate_pad_numbers_are_jumpers no)
		(fp_line
			(start -0.7874 -0.4064)
			(end 0.7874 -0.4064)
			(stroke
				(width 0.1524)
				(type default)
			)
			(layer "F.SilkS")
		)
		(fp_line
			(start -0.7874 0.4064)
			(end -0.7874 -0.4064)
			(stroke
				(width 0.1524)
				(type default)
			)
			(layer "F.SilkS")
		)
		(fp_line
			(start 0.7874 -0.4064)
			(end 0.7874 0.4064)
			(stroke
				(width 0.1524)
				(type default)
			)
			(layer "F.SilkS")
		)
		(fp_line
			(start 0.7874 0.4064)
			(end -0.7874 0.4064)
			(stroke
				(width 0.1524)
				(type default)
			)
			(layer "F.SilkS")
		)
		(fp_line
			(start -0.67945 -0.305054)
			(end -0.12065 -0.305054)
			(stroke
				(width 0.1)
				(type default)
			)
			(layer "F.Fab")
		)
		(fp_line
			(start -0.67945 0.3048)
			(end -0.67945 -0.305054)
			(stroke
				(width 0.1)
				(type default)
			)
			(layer "F.Fab")
		)
		(fp_line
			(start -0.12065 -0.305054)
			(end -0.12065 -0.2794)
			(stroke
				(width 0.1)
				(type default)
			)
			(layer "F.Fab")
		)
		(fp_line
			(start -0.12065 -0.2794)
			(end 0.12065 -0.2794)
			(stroke
				(width 0.1)
				(type default)
			)
			(layer "F.Fab")
		)
		(fp_line
			(start -0.12065 0.2794)
			(end -0.12065 0.3048)
			(stroke
				(width 0.1)
				(type default)
			)
			(layer "F.Fab")
		)
		(fp_line
			(start -0.12065 0.3048)
			(end -0.67945 0.3048)
			(stroke
				(width 0.1)
				(type default)
			)
			(layer "F.Fab")
		)
		(fp_line
			(start 0.120396 0.2794)
			(end -0.12065 0.2794)
			(stroke
				(width 0.1)
				(type default)
			)
			(layer "F.Fab")
		)
		(fp_line
			(start 0.120396 0.3048)
			(end 0.120396 0.2794)
			(stroke
				(width 0.1)
				(type default)
			)
			(layer "F.Fab")
		)
		(fp_line
			(start 0.12065 -0.3048)
			(end 0.67945 -0.3048)
			(stroke
				(width 0.1)
				(type default)
			)
			(layer "F.Fab")
		)
		(fp_line
			(start 0.12065 -0.2794)
			(end 0.12065 -0.3048)
			(stroke
				(width 0.1)
				(type default)
			)
			(layer "F.Fab")
		)
		(fp_line
			(start 0.67945 -0.3048)
			(end 0.67945 0.3048)
			(stroke
				(width 0.1)
				(type default)
			)
			(layer "F.Fab")
		)
		(fp_line
			(start 0.67945 0.3048)
			(end 0.120396 0.3048)
			(stroke
				(width 0.1)
				(type default)
			)
			(layer "F.Fab")
		)
		(pad "1" smd circle
			(at -0.40005 0)
			(size 0 0)
			(layers "F.Cu" "F.Mask" "F.Paste")
			(net "SW_P12V_PVCCIN_CPU0_FLT")
		)
		(pad "2" smd circle
			(at 0.40005 0)
			(size 0 0)
			(layers "F.Cu" "F.Mask" "F.Paste")
			(net "GND")
		)
	)
	(footprint ""
		(layer "F.Cu")
		(at 439.49366 -106.38536 90)
		(property "Reference" "C2376"
			(at 0 0 90)
			(layer "F.SilkS")
			(hide yes)
			(effects
				(font
					(size 1.27 1.27)
				)
			)
		)
		(property "Value" ""
			(at 0 0 90)
			(layer "F.Fab")
			(effects
				(font
					(size 1.27 1.27)
				)
			)
		)
		(duplicate_pad_numbers_are_jumpers no)
		(fp_line
			(start 0.7874 -0.4064)
			(end 0.7874 0.4064)
			(stroke
				(width 0.1524)
				(type default)
			)
			(layer "F.SilkS")
		)
		(fp_line
			(start -0.7874 -0.4064)
			(end 0.7874 -0.4064)
			(stroke
				(width 0.1524)
				(type default)
			)
			(layer "F.SilkS")
		)
		(fp_line
			(start 0.7874 0.4064)
			(end -0.7874 0.4064)
			(stroke
				(width 0.1524)
				(type default)
			)
			(layer "F.SilkS")
		)
		(fp_line
			(start -0.7874 0.4064)
			(end -0.7874 -0.4064)
			(stroke
				(width 0.1524)
				(type default)
			)
			(layer "F.SilkS")
		)
		(fp_line
			(start -0.12065 -0.305054)
			(end -0.12065 -0.2794)
			(stroke
				(width 0.1)
				(type default)
			)
			(layer "F.Fab")
		)
		(fp_line
			(start -0.67945 -0.305054)
			(end -0.12065 -0.305054)
			(stroke
				(width 0.1)
				(type default)
			)
			(layer "F.Fab")
		)
		(fp_line
			(start 0.67945 -0.3048)
			(end 0.67945 0.3048)
			(stroke
				(width 0.1)
				(type default)
			)
			(layer "F.Fab")
		)
		(fp_line
			(start 0.12065 -0.3048)
			(end 0.67945 -0.3048)
			(stroke
				(width 0.1)
				(type default)
			)
			(layer "F.Fab")
		)
		(fp_line
			(start 0.12065 -0.2794)
			(end 0.12065 -0.3048)
			(stroke
				(width 0.1)
				(type default)
			)
			(layer "F.Fab")
		)
		(fp_line
			(start -0.12065 -0.2794)
			(end 0.12065 -0.2794)
			(stroke
				(width 0.1)
				(type default)
			)
			(layer "F.Fab")
		)
		(fp_line
			(start 0.120396 0.2794)
			(end -0.12065 0.2794)
			(stroke
				(width 0.1)
				(type default)
			)
			(layer "F.Fab")
		)
		(fp_line
			(start -0.12065 0.2794)
			(end -0.12065 0.3048)
			(stroke
				(width 0.1)
				(type default)
			)
			(layer "F.Fab")
		)
		(fp_line
			(start 0.67945 0.3048)
			(end 0.120396 0.3048)
			(stroke
				(width 0.1)
				(type default)
			)
			(layer "F.Fab")
		)
		(fp_line
			(start 0.120396 0.3048)
			(end 0.120396 0.2794)
			(stroke
				(width 0.1)
				(type default)
			)
			(layer "F.Fab")
		)
		(fp_line
			(start -0.12065 0.3048)
			(end -0.67945 0.3048)
			(stroke
				(width 0.1)
				(type default)
			)
			(layer "F.Fab")
		)
		(fp_line
			(start -0.67945 0.3048)
			(end -0.67945 -0.305054)
			(stroke
				(width 0.1)
				(type default)
			)
			(layer "F.Fab")
		)
		(pad "1" smd circle
			(at -0.40005 0 90)
			(size 0 0)
			(layers "F.Cu" "F.Mask" "F.Paste")
			(net "P3V3_AUX")
		)
		(pad "2" smd circle
			(at 0.40005 0 90)
			(size 0 0)
			(layers "F.Cu" "F.Mask" "F.Paste")
			(net "GND")
		)
	)
)
